# T6G (Grand Teton) — schematic netlist excerpt (pin names and nets, part order shuffled) for the footprints in the layout excerpt that follows; sources: Cadence DE-HDL packaged netlist, KiCad conversion of 04192023_DAF0TMB3IC0_F0TG_MB_C_brd_V02_OCP.brd

R6153  Q_RES  0 5% CHIP  pkg 0201LF  page 113 : A = P2E_MB_BMC_TX_C_DN<0> ; B = P2E_MB_BMC_TX_C_R1_DN<0>
R249  Q_RES  33 5% CHIP  pkg 0402LF  page 28 : A = FM_CPU0_SLP_S3_N ; B = CPU0_SLP_S3_N
C8  Q_CAP  0.1UF 25V 10% X7R  pkg 0402  page 124 : A = P3V3_AUX ; B = GND

(kicad_pcb
	(version 20260206)
	(generator "pcbnew")
	(generator_version "10.0")
	(general
		(thickness 1.6)
		(legacy_teardrops no)
	)
	(paper "A4")
	(title_block
		(title "04192023_DAF0TMB3IC0_F0TG_MB_C_brd_V02_OCP.brd")
		(comment 1 "Grand Teton / footprints 578-580 of 8354")
	)
	(layers
		(0 "F.Cu" signal "TOP")
		(4 "In1.Cu" signal "GND")
		(6 "In2.Cu" signal "IN1")
		(8 "In3.Cu" signal "GND1")
		(10 "In4.Cu" signal "IN2")
		(12 "In5.Cu" signal "GND2")
		(14 "In6.Cu" signal "IN3")
		(16 "In7.Cu" signal "GND3")
		(18 "In8.Cu" signal "VCC")
		(20 "In9.Cu" signal "VCC1")
		(22 "In10.Cu" signal "GND4")
		(24 "In11.Cu" signal "IN4")
		(26 "In12.Cu" signal "GND5")
		(28 "In13.Cu" signal "IN5")
		(30 "In14.Cu" signal "GND6")
		(32 "In15.Cu" signal "IN6")
		(34 "In16.Cu" signal "GND7")
		(2 "B.Cu" signal "BOTTOM")
		(9 "F.Adhes" user "F.Adhesive")
		(11 "B.Adhes" user "B.Adhesive")
		(13 "F.Paste" user "Package Geometry/Pastemask Top")
		(15 "B.Paste" user "Package Geometry/Pastemask Bottom")
		(5 "F.SilkS" user "Ref Des/Silkscreen Top")
		(7 "B.SilkS" user "Ref Des/Silkscreen Bottom")
		(1 "F.Mask" user "Board Geometry/Soldermask Top")
		(3 "B.Mask" user "Board Geometry/Soldermask Bottom")
		(17 "Dwgs.User" user "User.Drawings")
		(19 "Cmts.User" user "User.Comments")
		(21 "Eco1.User" user "User.Eco1")
		(23 "Eco2.User" user "User.Eco2")
		(25 "Edge.Cuts" user "Board Geometry/Outline")
		(27 "Margin" user)
		(31 "F.CrtYd" user "Package Geometry/Place Bound Top")
		(29 "B.CrtYd" user "Package Geometry/Place Bound Bottom")
		(35 "F.Fab" user "Ref Des/Assembly Top")
		(33 "B.Fab" user "Ref Des/Assembly Bottom")
	)
	(footprint ""
		(layer "F.Cu")
		(at 352.05543 -434.857652 180)
		(property "Reference" "C8"
			(at 0 0 180)
			(layer "F.SilkS")
			(hide yes)
			(effects
				(font
					(size 1.27 1.27)
				)
			)
		)
		(property "Value" ""
			(at 0 0 180)
			(layer "F.Fab")
			(effects
				(font
					(size 1.27 1.27)
				)
			)
		)
		(duplicate_pad_numbers_are_jumpers no)
		(fp_line
			(start 0.7874 0.4064)
			(end -0.7874 0.4064)
			(stroke
				(width 0.1524)
				(type default)
			)
			(layer "F.SilkS")
		)
		(fp_line
			(start 0.7874 -0.4064)
			(end 0.7874 0.4064)
			(stroke
				(width 0.1524)
				(type default)
			)
			(layer "F.SilkS")
		)
		(fp_line
			(start -0.7874 0.4064)
			(end -0.7874 -0.4064)
			(stroke
				(width 0.1524)
				(type default)
			)
			(layer "F.SilkS")
		)
		(fp_line
			(start -0.7874 -0.4064)
			(end 0.7874 -0.4064)
			(stroke
				(width 0.1524)
				(type default)
			)
			(layer "F.SilkS")
		)
		(fp_line
			(start 0.67945 0.3048)
			(end 0.120396 0.3048)
			(stroke
				(width 0.1)
				(type default)
			)
			(layer "F.Fab")
		)
		(fp_line
			(start 0.67945 -0.3048)
			(end 0.67945 0.3048)
			(stroke
				(width 0.1)
				(type default)
			)
			(layer "F.Fab")
		)
		(fp_line
			(start 0.12065 -0.2794)
			(end 0.12065 -0.3048)
			(stroke
				(width 0.1)
				(type default)
			)
			(layer "F.Fab")
		)
		(fp_line
			(start 0.12065 -0.3048)
			(end 0.67945 -0.3048)
			(stroke
				(width 0.1)
				(type default)
			)
			(layer "F.Fab")
		)
		(fp_line
			(start 0.120396 0.3048)
			(end 0.120396 0.2794)
			(stroke
				(width 0.1)
				(type default)
			)
			(layer "F.Fab")
		)
		(fp_line
			(start 0.120396 0.2794)
			(end -0.12065 0.2794)
			(stroke
				(width 0.1)
				(type default)
			)
			(layer "F.Fab")
		)
		(fp_line
			(start -0.12065 0.3048)
			(end -0.67945 0.3048)
			(stroke
				(width 0.1)
				(type default)
			)
			(layer "F.Fab")
		)
		(fp_line
			(start -0.12065 0.2794)
			(end -0.12065 0.3048)
			(stroke
				(width 0.1)
				(type default)
			)
			(layer "F.Fab")
		)
		(fp_line
			(start -0.12065 -0.2794)
			(end 0.12065 -0.2794)
			(stroke
				(width 0.1)
				(type default)
			)
			(layer "F.Fab")
		)
		(fp_line
			(start -0.12065 -0.305054)
			(end -0.12065 -0.2794)
			(stroke
				(width 0.1)
				(type default)
			)
			(layer "F.Fab")
		)
		(fp_line
			(start -0.67945 0.3048)
			(end -0.67945 -0.305054)
			(stroke
				(width 0.1)
				(type default)
			)
			(layer "F.Fab")
		)
		(fp_line
			(start -0.67945 -0.305054)
			(end -0.12065 -0.305054)
			(stroke
				(width 0.1)
				(type default)
			)
			(layer "F.Fab")
		)
		(pad "1" smd circle
			(at -0.40005 0 180)
			(size 0 0)
			(layers "F.Cu" "F.Mask" "F.Paste")
			(net "P3V3_AUX")
		)
		(pad "2" smd circle
			(at 0.40005 0 180)
			(size 0 0)
			(layers "F.Cu" "F.Mask" "F.Paste")
			(net "GND")
		)
	)
	(footprint ""
		(layer "F.Cu")
		(at 39.309294 -423.21734 180)
		(property "Reference" "R6153"
			(at 0 0 180)
			(layer "F.SilkS")
			(hide yes)
			(effects
				(font
					(size 1.27 1.27)
				)
			)
		)
		(property "Value" ""
			(at 0 0 180)
			(layer "F.Fab")
			(effects
				(font
					(size 1.27 1.27)
				)
			)
		)
		(duplicate_pad_numbers_are_jumpers no)
		(fp_line
			(start 0.32512 0.175006)
			(end -0.32512 0.175006)
			(stroke
				(width 0.1)
				(type default)
			)
			(layer "F.Fab")
		)
		(fp_line
			(start 0.32512 -0.175006)
			(end 0.32512 0.175006)
			(stroke
				(width 0.1)
				(type default)
			)
			(layer "F.Fab")
		)
		(fp_line
			(start -0.32512 0.175006)
			(end -0.32512 -0.175006)
			(stroke
				(width 0.1)
				(type default)
			)
			(layer "F.Fab")
		)
		(fp_line
			(start -0.32512 -0.175006)
			(end 0.32512 -0.175006)
			(stroke
				(width 0.1)
				(type default)
			)
			(layer "F.Fab")
		)
		(pad "1" smd rect
			(at -0.2667 0 180)
			(size 0.3048 0.381)
			(layers "F.Cu" "F.Mask" "F.Paste")
			(net "P2E_MB_BMC_TX_C_DN<0>")
		)
		(pad "2" smd rect
			(at 0.2667 0)
			(size 0.3048 0.381)
			(layers "F.Cu" "F.Mask" "F.Paste")
			(net "P2E_MB_BMC_TX_C_R1_DN<0>")
		)
	)
	(footprint ""
		(layer "F.Cu")
		(at 175.895 -129.377948 90)
		(property "Reference" "R249"
			(at 0 0 90)
			(layer "F.SilkS")
			(hide yes)
			(effects
				(font
					(size 1.27 1.27)
				)
			)
		)
		(property "Value" ""
			(at 0 0 90)
			(layer "F.Fab")
			(effects
				(font
					(size 1.27 1.27)
				)
			)
		)
		(duplicate_pad_numbers_are_jumpers no)
		(fp_line
			(start 0.7874 -0.4064)
			(end 0.7874 0.4064)
			(stroke
				(width 0.1524)
				(type default)
			)
			(layer "F.SilkS")
		)
		(fp_line
			(start -0.7874 -0.4064)
			(end 0.7874 -0.4064)
			(stroke
				(width 0.1524)
				(type default)
			)
			(layer "F.SilkS")
		)
		(fp_line
			(start 0.7874 0.4064)
			(end -0.7874 0.4064)
			(stroke
				(width 0.1524)
				(type default)
			)
			(layer "F.SilkS")
		)
		(fp_line
			(start -0.7874 0.4064)
			(end -0.7874 -0.4064)
			(stroke
				(width 0.1524)
				(type default)
			)
			(layer "F.SilkS")
		)
		(fp_line
			(start -0.12065 -0.305054)
			(end -0.12065 -0.2794)
			(stroke
				(width 0.1)
				(type default)
			)
			(layer "F.Fab")
		)
		(fp_line
			(start -0.67945 -0.305054)
			(end -0.12065 -0.305054)
			(stroke
				(width 0.1)
				(type default)
			)
			(layer "F.Fab")
		)
		(fp_line
			(start 0.67945 -0.3048)
			(end 0.67945 0.3048)
			(stroke
				(width 0.1)
				(type default)
			)
			(layer "F.Fab")
		)
		(fp_line
			(start 0.12065 -0.3048)
			(end 0.67945 -0.3048)
			(stroke
				(width 0.1)
				(type default)
			)
			(layer "F.Fab")
		)
		(fp_line
			(start 0.12065 -0.2794)
			(end 0.12065 -0.3048)
			(stroke
				(width 0.1)
				(type default)
			)
			(layer "F.Fab")
		)
		(fp_line
			(start -0.12065 -0.2794)
			(end 0.12065 -0.2794)
			(stroke
				(width 0.1)
				(type default)
			)
			(layer "F.Fab")
		)
		(fp_line
			(start 0.120396 0.2794)
			(end -0.12065 0.2794)
			(stroke
				(width 0.1)
				(type default)
			)
			(layer "F.Fab")
		)
		(fp_line
			(start -0.12065 0.2794)
			(end -0.12065 0.3048)
			(stroke
				(width 0.1)
				(type default)
			)
			(layer "F.Fab")
		)
		(fp_line
			(start 0.67945 0.3048)
			(end 0.120396 0.3048)
			(stroke
				(width 0.1)
				(type default)
			)
			(layer "F.Fab")
		)
		(fp_line
			(start 0.120396 0.3048)
			(end 0.120396 0.2794)
			(stroke
				(width 0.1)
				(type default)
			)
			(layer "F.Fab")
		)
		(fp_line
			(start -0.12065 0.3048)
			(end -0.67945 0.3048)
			(stroke
				(width 0.1)
				(type default)
			)
			(layer "F.Fab")
		)
		(fp_line
			(start -0.67945 0.3048)
			(end -0.67945 -0.305054)
			(stroke
				(width 0.1)
				(type default)
			)
			(layer "F.Fab")
		)
		(pad "1" smd circle
			(at -0.40005 0 90)
			(size 0 0)
			(layers "F.Cu" "F.Mask" "F.Paste")
			(net "FM_CPU0_SLP_S3_N")
		)
		(pad "2" smd circle
			(at 0.40005 0 90)
			(size 0 0)
			(layers "F.Cu" "F.Mask" "F.Paste")
			(net "CPU0_SLP_S3_N")
		)
	)
)
